#ISCELL
  pure_quanta quanta_title_block_c *
  *
#CELL
  pure_quanta socket4677_azif0045p001c01cs *
  page49_i2
